(kicad_pcb
	(version 20221018)
	(generator pcbnew)
	(general
    (thickness 1.7403)
  )
	(paper "A4")
	(title_block
    (title "Data Center RDIMM DDR4 Tester")
    (date "2024-09-30")
    (rev "1.2.4")
		(comment 9 "footprints 495-503 of 690")
	)
	(layers
    (0 "F.Cu" signal)
    (1 "In1.Cu" power)
    (2 "In2.Cu" signal)
    (3 "In3.Cu" power)
    (4 "In4.Cu" power)
    (5 "In5.Cu" signal)
    (6 "In6.Cu" power)
    (7 "In7.Cu" signal)
    (8 "In8.Cu" power)
    (9 "In9.Cu" signal)
    (10 "In10.Cu" power)
    (31 "B.Cu" signal)
    (32 "B.Adhes" user "B.Adhesive")
    (33 "F.Adhes" user "F.Adhesive")
    (34 "B.Paste" user)
    (35 "F.Paste" user)
    (36 "B.SilkS" user "B.Silkscreen")
    (37 "F.SilkS" user "F.Silkscreen")
    (38 "B.Mask" user)
    (39 "F.Mask" user)
    (40 "Dwgs.User" user "User.Drawings")
    (41 "Cmts.User" user "User.Comments")
    (42 "Eco1.User" user "User.Eco1")
    (43 "Eco2.User" user "User.Eco2")
    (44 "Edge.Cuts" user)
    (45 "Margin" user)
    (46 "B.CrtYd" user "B.Courtyard")
    (47 "F.CrtYd" user "F.Courtyard")
    (48 "B.Fab" user)
    (49 "F.Fab" user)
  )
	(footprint "data-center-rdimm-ddr4-tester-footprints:R_0402_1005Metric" (layer "B.Cu")
    (at 159.636328 87.320008 90)
    (descr "Resistor SMD 0402")
    (tags "resistor SMD 0402")
    (property "Author" "Antmicro")
    (property "License" "Apache-2.0")
    (property "MPN" "CR0402-FX-1002GLF")
    (property "Manufacturer" "Bourns")
    (property "Sheetfile" "ethernet.kicad_sch")
    (property "Sheetname" "Ethernet")
    (property "Tolerance" "1%")
    (property "Val" "10k")
    (property "ki_description" "10k resistor in 0402 package with 1% tolerance")
    (attr smd)
    (fp_text reference "R72" (at 1.170008 8.103672 270) (layer "B.SilkS")
        (effects (font (size 0.7 0.7) (thickness 0.15)) (justify left bottom mirror))
    )
    (fp_text value "R_10k_0402" (at 0 -1.4 270) (layer "B.Fab") hide
        (effects (font (size 0.7 0.7) (thickness 0.15)) (justify left bottom mirror))
    )
    (fp_text user "${REFERENCE}" (at -0.95 -3.168 270) (layer "B.Fab") hide
        (effects (font (size 0.7 0.7) (thickness 0.15)) (justify left bottom mirror))
    )
    (fp_text user "Author: Antmicro" (at -0.95 -4.169 270) (layer "B.Fab") hide
        (effects (font (size 0.7 0.7) (thickness 0.15)) (justify left bottom mirror))
    )
    (fp_text user "License: Apache-2.0" (at -0.95 -5.169 270) (layer "B.Fab") hide
        (effects (font (size 0.7 0.7) (thickness 0.15)) (justify left bottom mirror))
    )
    (fp_rect (start -0.93 0.47) (end 0.93 -0.47)
      (stroke (width 0.05) (type solid)) (fill none) (layer "B.CrtYd"))
    (fp_rect (start -0.5 0.25) (end 0.5 -0.25)
      (stroke (width 0.15) (type solid)) (fill none) (layer "B.Fab"))
    (pad "1" smd roundrect (at -0.485 0 90) (size 0.59 0.64) (layers "B.Cu" "B.Paste" "B.Mask") (roundrect_rratio 0.25)
      (net 41 "ETH_RXD2") (pintype "passive"))
    (pad "2" smd roundrect (at 0.485 0 90) (size 0.59 0.64) (layers "B.Cu" "B.Paste" "B.Mask") (roundrect_rratio 0.25)
      (net 143 "3V3_SYS") (pintype "passive"))
  )
	(footprint "data-center-rdimm-ddr4-tester-footprints:C_0201" (layer "B.Cu")
    (at 187.186328 88.560008 90)
    (descr "Capacitor SMD 0201")
    (tags "capacitor SMD 0201")
    (property "Author" "Antmicro")
    (property "Dielectric" "")
    (property "License" "Apache-2.0")
    (property "MPN" "CC0201KRX6S5BB104")
    (property "Manufacturer" "Yaego")
    (property "Sheetfile" "fpga-power.kicad_sch")
    (property "Sheetname" "FPGA power")
    (property "Val" "100n")
    (property "Voltage" "")
    (property "ki_description" " ")
    (attr smd)
    (fp_text reference "C49" (at 10.330008 18.203672 270) (layer "B.SilkS")
        (effects (font (size 0.7 0.7) (thickness 0.15)) (justify left bottom mirror))
    )
    (fp_text value "C_100n_0201" (at 0 -1.4 270) (layer "B.Fab") hide
        (effects (font (size 0.7 0.7) (thickness 0.15)) (justify left bottom mirror))
    )
    (fp_text user "Author: Antmicro" (at -0.72 -5.4 270) (layer "B.Fab") hide
        (effects (font (size 0.7 0.7) (thickness 0.15)) (justify left bottom mirror))
    )
    (fp_text user "${REFERENCE}" (at -0.72 -3.4 270) (layer "B.Fab") hide
        (effects (font (size 0.7 0.7) (thickness 0.15)) (justify left bottom mirror))
    )
    (fp_text user "License: Apache-2.0" (at -0.72 -4.4 270) (layer "B.Fab") hide
        (effects (font (size 0.7 0.7) (thickness 0.15)) (justify left bottom mirror))
    )
    (fp_rect (start -0.72 0.38) (end 0.72 -0.38)
      (stroke (width 0.05) (type solid)) (fill none) (layer "B.CrtYd"))
    (fp_rect (start 0.3 -0.15) (end -0.301 0.149)
      (stroke (width 0.15) (type solid)) (fill none) (layer "B.Fab"))
    (pad "" smd roundrect (at -0.349 0.002 90) (size 0.318 0.36) (layers "B.Paste") (roundrect_rratio 0.25))
    (pad "" smd roundrect (at 0.341 0.002 90) (size 0.318 0.36) (layers "B.Paste") (roundrect_rratio 0.25))
    (pad "1" smd roundrect (at -0.321 0.002 90) (size 0.46 0.4) (layers "B.Cu" "B.Mask") (roundrect_rratio 0.25)
      (net 144 "1V8_SYS") (pintype "passive"))
    (pad "2" smd roundrect (at 0.32 0.002 90) (size 0.46 0.4) (layers "B.Cu" "B.Mask") (roundrect_rratio 0.25)
      (net 9 "GND") (pintype "passive"))
  )
	(footprint "data-center-rdimm-ddr4-tester-footprints:C_0201" (layer "B.Cu")
    (at 182.186328 88.560008 90)
    (descr "Capacitor SMD 0201")
    (tags "capacitor SMD 0201")
    (property "Author" "Antmicro")
    (property "Dielectric" "")
    (property "License" "Apache-2.0")
    (property "MPN" "CC0201KRX6S5BB104")
    (property "Manufacturer" "Yaego")
    (property "Sheetfile" "fpga-power.kicad_sch")
    (property "Sheetname" "FPGA power")
    (property "Val" "100n")
    (property "Voltage" "")
    (property "ki_description" " ")
    (attr smd)
    (fp_text reference "C59" (at 10.270008 18.063672 270) (layer "B.SilkS")
        (effects (font (size 0.7 0.7) (thickness 0.15)) (justify left bottom mirror))
    )
    (fp_text value "C_100n_0201" (at 0 -1.4 270) (layer "B.Fab") hide
        (effects (font (size 0.7 0.7) (thickness 0.15)) (justify left bottom mirror))
    )
    (fp_text user "Author: Antmicro" (at -0.72 -5.4 270) (layer "B.Fab") hide
        (effects (font (size 0.7 0.7) (thickness 0.15)) (justify left bottom mirror))
    )
    (fp_text user "License: Apache-2.0" (at -0.72 -4.4 270) (layer "B.Fab") hide
        (effects (font (size 0.7 0.7) (thickness 0.15)) (justify left bottom mirror))
    )
    (fp_text user "${REFERENCE}" (at -0.72 -3.4 270) (layer "B.Fab") hide
        (effects (font (size 0.7 0.7) (thickness 0.15)) (justify left bottom mirror))
    )
    (fp_rect (start -0.72 0.38) (end 0.72 -0.38)
      (stroke (width 0.05) (type solid)) (fill none) (layer "B.CrtYd"))
    (fp_rect (start 0.3 -0.15) (end -0.301 0.149)
      (stroke (width 0.15) (type solid)) (fill none) (layer "B.Fab"))
    (pad "" smd roundrect (at -0.349 0.002 90) (size 0.318 0.36) (layers "B.Paste") (roundrect_rratio 0.25))
    (pad "" smd roundrect (at 0.341 0.002 90) (size 0.318 0.36) (layers "B.Paste") (roundrect_rratio 0.25))
    (pad "1" smd roundrect (at -0.321 0.002 90) (size 0.46 0.4) (layers "B.Cu" "B.Mask") (roundrect_rratio 0.25)
      (net 147 "1V0_SYS") (pintype "passive"))
    (pad "2" smd roundrect (at 0.32 0.002 90) (size 0.46 0.4) (layers "B.Cu" "B.Mask") (roundrect_rratio 0.25)
      (net 9 "GND") (pintype "passive"))
  )
	(footprint "data-center-rdimm-ddr4-tester-footprints:C_0603_1608Metric" (layer "B.Cu")
    (at 185.625 90.725 90)
    (descr "Capacitor SMD 0603")
    (tags "capacitor 0603")
    (property "Author" "Antmicro")
    (property "Dielectric" "")
    (property "License" "Apache-2.0")
    (property "MPN" "GRM188R60J476ME15D")
    (property "Manufacturer" "Murata")
    (property "Sheetfile" "fpga-power.kicad_sch")
    (property "Sheetname" "FPGA power")
    (property "Val" "47u")
    (property "Voltage" "")
    (property "ki_description" " ")
    (attr smd)
    (fp_text reference "C22" (at 10.195 18.315 270) (layer "B.SilkS")
        (effects (font (size 0.7 0.7) (thickness 0.15)) (justify left bottom mirror))
    )
    (fp_text value "C_47u_0603" (at 0 -1.6 270) (layer "B.Fab") hide
        (effects (font (size 0.7 0.7) (thickness 0.15)) (justify left bottom mirror))
    )
    (fp_text user "Author: Antmicro" (at -1.682 -4.894 270) (layer "B.Fab") hide
        (effects (font (size 0.7 0.7) (thickness 0.15)) (justify left bottom mirror))
    )
    (fp_text user "License: Apache-2.0" (at -1.682 -5.895 270) (layer "B.Fab") hide
        (effects (font (size 0.7 0.7) (thickness 0.15)) (justify left bottom mirror))
    )
    (fp_text user "${REFERENCE}" (at -1.682 -3.895 270) (layer "B.Fab") hide
        (effects (font (size 0.7 0.7) (thickness 0.15)) (justify left bottom mirror))
    )
    (fp_line (start -0.3 -0.3) (end 0.3 -0.3)
      (stroke (width 0.15) (type solid)) (layer "B.SilkS"))
    (fp_line (start -0.3 0.3) (end 0.3 0.3)
      (stroke (width 0.15) (type solid)) (layer "B.SilkS"))
    (fp_rect (start -1.24 0.7) (end 1.24 -0.7)
      (stroke (width 0.05) (type solid)) (fill none) (layer "B.CrtYd"))
    (fp_rect (start -0.8 0.4) (end 0.8 -0.4)
      (stroke (width 0.15) (type solid)) (fill none) (layer "B.Fab"))
    (pad "1" smd roundrect (at -0.7 0 90) (size 0.6 0.8) (layers "B.Cu" "B.Paste" "B.Mask") (roundrect_rratio 0.2)
      (net 144 "1V8_SYS") (pintype "passive"))
    (pad "2" smd roundrect (at 0.7 0 90) (size 0.6 0.8) (layers "B.Cu" "B.Paste" "B.Mask") (roundrect_rratio 0.2)
      (net 9 "GND") (pintype "passive"))
  )
	(footprint "data-center-rdimm-ddr4-tester-footprints:C_0603_1608Metric" (layer "B.Cu")
    (at 188.775 98.35 90)
    (descr "Capacitor SMD 0603")
    (tags "capacitor 0603")
    (property "Author" "Antmicro")
    (property "Dielectric" "")
    (property "License" "Apache-2.0")
    (property "MPN" "GRM188R60J476ME15D")
    (property "Manufacturer" "Murata")
    (property "Sheetfile" "fpga-power.kicad_sch")
    (property "Sheetname" "FPGA power")
    (property "Val" "47u")
    (property "Voltage" "")
    (property "ki_description" " ")
    (attr smd)
    (fp_text reference "C114" (at -0.95 0.325 270) (layer "B.SilkS")
        (effects (font (size 0.7 0.7) (thickness 0.15)) (justify left bottom mirror))
    )
    (fp_text value "C_47u_0603" (at 0 -1.6 270) (layer "B.Fab") hide
        (effects (font (size 0.7 0.7) (thickness 0.15)) (justify left bottom mirror))
    )
    (fp_text user "License: Apache-2.0" (at -1.682 -5.895 270) (layer "B.Fab") hide
        (effects (font (size 0.7 0.7) (thickness 0.15)) (justify left bottom mirror))
    )
    (fp_text user "Author: Antmicro" (at -1.682 -4.894 270) (layer "B.Fab") hide
        (effects (font (size 0.7 0.7) (thickness 0.15)) (justify left bottom mirror))
    )
    (fp_text user "${REFERENCE}" (at -1.682 -3.895 270) (layer "B.Fab") hide
        (effects (font (size 0.7 0.7) (thickness 0.15)) (justify left bottom mirror))
    )
    (fp_line (start -0.3 -0.3) (end 0.3 -0.3)
      (stroke (width 0.15) (type solid)) (layer "B.SilkS"))
    (fp_line (start -0.3 0.3) (end 0.3 0.3)
      (stroke (width 0.15) (type solid)) (layer "B.SilkS"))
    (fp_rect (start -1.24 0.7) (end 1.24 -0.7)
      (stroke (width 0.05) (type solid)) (fill none) (layer "B.CrtYd"))
    (fp_rect (start -0.8 0.4) (end 0.8 -0.4)
      (stroke (width 0.15) (type solid)) (fill none) (layer "B.Fab"))
    (pad "1" smd roundrect (at -0.7 0 90) (size 0.6 0.8) (layers "B.Cu" "B.Paste" "B.Mask") (roundrect_rratio 0.2)
      (net 144 "1V8_SYS") (pintype "passive"))
    (pad "2" smd roundrect (at 0.7 0 90) (size 0.6 0.8) (layers "B.Cu" "B.Paste" "B.Mask") (roundrect_rratio 0.2)
      (net 9 "GND") (pintype "passive"))
  )
	(footprint "data-center-rdimm-ddr4-tester-footprints:C_0201" (layer "B.Cu")
    (at 182.186328 93.560008 90)
    (descr "Capacitor SMD 0201")
    (tags "capacitor SMD 0201")
    (property "Author" "Antmicro")
    (property "Dielectric" "")
    (property "License" "Apache-2.0")
    (property "MPN" "CC0201KRX6S5BB104")
    (property "Manufacturer" "Yaego")
    (property "Sheetfile" "fpga-power.kicad_sch")
    (property "Sheetname" "FPGA power")
    (property "Val" "100n")
    (property "Voltage" "")
    (property "ki_description" " ")
    (attr smd)
    (fp_text reference "C67" (at 10.360008 18.393672 270) (layer "B.SilkS")
        (effects (font (size 0.7 0.7) (thickness 0.15)) (justify left bottom mirror))
    )
    (fp_text value "C_100n_0201" (at 0 -1.4 270) (layer "B.Fab") hide
        (effects (font (size 0.7 0.7) (thickness 0.15)) (justify left bottom mirror))
    )
    (fp_text user "${REFERENCE}" (at -0.72 -3.4 270) (layer "B.Fab") hide
        (effects (font (size 0.7 0.7) (thickness 0.15)) (justify left bottom mirror))
    )
    (fp_text user "Author: Antmicro" (at -0.72 -5.4 270) (layer "B.Fab") hide
        (effects (font (size 0.7 0.7) (thickness 0.15)) (justify left bottom mirror))
    )
    (fp_text user "License: Apache-2.0" (at -0.72 -4.4 270) (layer "B.Fab") hide
        (effects (font (size 0.7 0.7) (thickness 0.15)) (justify left bottom mirror))
    )
    (fp_rect (start -0.72 0.38) (end 0.72 -0.38)
      (stroke (width 0.05) (type solid)) (fill none) (layer "B.CrtYd"))
    (fp_rect (start 0.3 -0.15) (end -0.301 0.149)
      (stroke (width 0.15) (type solid)) (fill none) (layer "B.Fab"))
    (pad "" smd roundrect (at -0.349 0.002 90) (size 0.318 0.36) (layers "B.Paste") (roundrect_rratio 0.25))
    (pad "" smd roundrect (at 0.341 0.002 90) (size 0.318 0.36) (layers "B.Paste") (roundrect_rratio 0.25))
    (pad "1" smd roundrect (at -0.321 0.002 90) (size 0.46 0.4) (layers "B.Cu" "B.Mask") (roundrect_rratio 0.25)
      (net 147 "1V0_SYS") (pintype "passive"))
    (pad "2" smd roundrect (at 0.32 0.002 90) (size 0.46 0.4) (layers "B.Cu" "B.Mask") (roundrect_rratio 0.25)
      (net 9 "GND") (pintype "passive"))
  )
	(footprint "data-center-rdimm-ddr4-tester-footprints:C_0603_1608Metric" (layer "B.Cu")
    (at 185.611328 95.585008 -90)
    (descr "Capacitor SMD 0603")
    (tags "capacitor 0603")
    (property "Author" "Antmicro")
    (property "Dielectric" "")
    (property "License" "Apache-2.0")
    (property "MPN" "GRM188R60J476ME15D")
    (property "Manufacturer" "Murata")
    (property "Sheetfile" "fpga-power.kicad_sch")
    (property "Sheetname" "FPGA power")
    (property "Val" "47u")
    (property "Voltage" "")
    (property "ki_description" " ")
    (attr smd)
    (fp_text reference "C25" (at -0.895008 0.611328 90) (layer "B.SilkS")
        (effects (font (size 0.7 0.7) (thickness 0.15)) (justify left bottom mirror))
    )
    (fp_text value "C_47u_0603" (at 0 -1.6 90) (layer "B.Fab") hide
        (effects (font (size 0.7 0.7) (thickness 0.15)) (justify left bottom mirror))
    )
    (fp_text user "Author: Antmicro" (at -1.682 -4.894 90) (layer "B.Fab") hide
        (effects (font (size 0.7 0.7) (thickness 0.15)) (justify left bottom mirror))
    )
    (fp_text user "${REFERENCE}" (at -1.682 -3.895 90) (layer "B.Fab") hide
        (effects (font (size 0.7 0.7) (thickness 0.15)) (justify left bottom mirror))
    )
    (fp_text user "License: Apache-2.0" (at -1.682 -5.895 90) (layer "B.Fab") hide
        (effects (font (size 0.7 0.7) (thickness 0.15)) (justify left bottom mirror))
    )
    (fp_line (start -0.3 -0.3) (end 0.3 -0.3)
      (stroke (width 0.15) (type solid)) (layer "B.SilkS"))
    (fp_line (start -0.3 0.3) (end 0.3 0.3)
      (stroke (width 0.15) (type solid)) (layer "B.SilkS"))
    (fp_rect (start -1.24 0.7) (end 1.24 -0.7)
      (stroke (width 0.05) (type solid)) (fill none) (layer "B.CrtYd"))
    (fp_rect (start -0.8 0.4) (end 0.8 -0.4)
      (stroke (width 0.15) (type solid)) (fill none) (layer "B.Fab"))
    (pad "1" smd roundrect (at -0.7 0 270) (size 0.6 0.8) (layers "B.Cu" "B.Paste" "B.Mask") (roundrect_rratio 0.2)
      (net 144 "1V8_SYS") (pintype "passive"))
    (pad "2" smd roundrect (at 0.7 0 270) (size 0.6 0.8) (layers "B.Cu" "B.Paste" "B.Mask") (roundrect_rratio 0.2)
      (net 9 "GND") (pintype "passive"))
  )
	(footprint "data-center-rdimm-ddr4-tester-footprints:C_0402_1005Metric" (layer "B.Cu")
    (at 193.086328 54.760008 90)
    (descr "Capacitor SMD 0402")
    (tags "capacitor SMD 0402")
    (property "Author" "Antmicro")
    (property "Dielectric" "X5R")
    (property "License" "Apache-2.0")
    (property "MPN" "GRM155R61H104KE14D")
    (property "Manufacturer" "Murata")
    (property "Sheetfile" "DDR4.kicad_sch")
    (property "Sheetname" "DDR4")
    (property "Val" "100n")
    (property "Voltage" "50V")
    (property "ki_description" " ")
    (attr smd)
    (fp_text reference "C160" (at 4.050008 0.423672 270) (layer "B.SilkS")
        (effects (font (size 0.7 0.7) (thickness 0.15)) (justify left bottom mirror))
    )
    (fp_text value "C_100n_0402" (at 0 -1.4 270) (layer "B.Fab") hide
        (effects (font (size 0.7 0.7) (thickness 0.15)) (justify left bottom mirror))
    )
    (fp_text user "License: Apache-2.0" (at -0.932 -5.17 270) (layer "B.Fab") hide
        (effects (font (size 0.7 0.7) (thickness 0.15)) (justify left bottom mirror))
    )
    (fp_text user "${REFERENCE}" (at -0.932 -3.168 270) (layer "B.Fab") hide
        (effects (font (size 0.7 0.7) (thickness 0.15)) (justify left bottom mirror))
    )
    (fp_text user "Author: Antmicro" (at -0.932 -4.17 270) (layer "B.Fab") hide
        (effects (font (size 0.7 0.7) (thickness 0.15)) (justify left bottom mirror))
    )
    (fp_rect (start -0.94 0.47) (end 0.94 -0.47)
      (stroke (width 0.05) (type solid)) (fill none) (layer "B.CrtYd"))
    (fp_rect (start -0.499 0.249) (end 0.499 -0.249)
      (stroke (width 0.15) (type solid)) (fill none) (layer "B.Fab"))
    (pad "1" smd roundrect (at -0.484 0 90) (size 0.59 0.64) (layers "B.Cu" "B.Paste" "B.Mask") (roundrect_rratio 0.25)
      (net 77 "VDDQ") (pintype "passive"))
    (pad "2" smd roundrect (at 0.484 0 90) (size 0.59 0.64) (layers "B.Cu" "B.Paste" "B.Mask") (roundrect_rratio 0.25)
      (net 9 "GND") (pintype "passive"))
  )
	(footprint "data-center-rdimm-ddr4-tester-footprints:C_0402_1005Metric" (layer "B.Cu")
    (at 190.536328 54.760008 90)
    (descr "Capacitor SMD 0402")
    (tags "capacitor SMD 0402")
    (property "Author" "Antmicro")
    (property "Dielectric" "X5R")
    (property "License" "Apache-2.0")
    (property "MPN" "GRM155R61H104KE14D")
    (property "Manufacturer" "Murata")
    (property "Sheetfile" "DDR4.kicad_sch")
    (property "Sheetname" "DDR4")
    (property "Val" "100n")
    (property "Voltage" "50V")
    (property "ki_description" " ")
    (attr smd)
    (fp_text reference "C161" (at 4.050008 0.423672 270) (layer "B.SilkS")
        (effects (font (size 0.7 0.7) (thickness 0.15)) (justify left bottom mirror))
    )
    (fp_text value "C_100n_0402" (at 0 -1.4 270) (layer "B.Fab") hide
        (effects (font (size 0.7 0.7) (thickness 0.15)) (justify left bottom mirror))
    )
    (fp_text user "License: Apache-2.0" (at -0.932 -5.17 270) (layer "B.Fab") hide
        (effects (font (size 0.7 0.7) (thickness 0.15)) (justify left bottom mirror))
    )
    (fp_text user "${REFERENCE}" (at -0.932 -3.168 270) (layer "B.Fab") hide
        (effects (font (size 0.7 0.7) (thickness 0.15)) (justify left bottom mirror))
    )
    (fp_text user "Author: Antmicro" (at -0.932 -4.17 270) (layer "B.Fab") hide
        (effects (font (size 0.7 0.7) (thickness 0.15)) (justify left bottom mirror))
    )
    (fp_rect (start -0.94 0.47) (end 0.94 -0.47)
      (stroke (width 0.05) (type solid)) (fill none) (layer "B.CrtYd"))
    (fp_rect (start -0.499 0.249) (end 0.499 -0.249)
      (stroke (width 0.15) (type solid)) (fill none) (layer "B.Fab"))
    (pad "1" smd roundrect (at -0.484 0 90) (size 0.59 0.64) (layers "B.Cu" "B.Paste" "B.Mask") (roundrect_rratio 0.25)
      (net 77 "VDDQ") (pintype "passive"))
    (pad "2" smd roundrect (at 0.484 0 90) (size 0.59 0.64) (layers "B.Cu" "B.Paste" "B.Mask") (roundrect_rratio 0.25)
      (net 9 "GND") (pintype "passive"))
  )
)
